(kicad_pcb
	(version 20260206)
	(generator "pcbnew")
	(generator_version "10.0")
	(general
		(thickness 1.6)
		(legacy_teardrops no)
	)
	(paper "A4")
	(title_block
		(title "Bryce Canyon_IOM_M2_16342-2_OCP.brd")
		(comment 1 "Bryce Canyon / footprints 306-312 of 1146")
	)
	(layers
		(0 "F.Cu" signal "TOP")
		(4 "In1.Cu" signal "L2GND")
		(6 "In2.Cu" signal "L3")
		(8 "In3.Cu" signal "L4VCC")
		(10 "In4.Cu" signal "L5VCC")
		(12 "In5.Cu" signal "L6")
		(14 "In6.Cu" signal "L7GND")
		(2 "B.Cu" signal "BOTTOM")
		(9 "F.Adhes" user "F.Adhesive")
		(11 "B.Adhes" user "B.Adhesive")
		(13 "F.Paste" user "Package Geometry/Pastemask Top")
		(15 "B.Paste" user "Package Geometry/Pastemask Bottom")
		(5 "F.SilkS" user "Ref Des/Silkscreen Top")
		(7 "B.SilkS" user "Ref Des/Silkscreen Bottom")
		(1 "F.Mask" user "Board Geometry/Soldermask Top")
		(3 "B.Mask" user "Board Geometry/Soldermask Bottom")
		(17 "Dwgs.User" user "User.Drawings")
		(19 "Cmts.User" user "User.Comments")
		(21 "Eco1.User" user "User.Eco1")
		(23 "Eco2.User" user "User.Eco2")
		(25 "Edge.Cuts" user "Board Geometry/Outline")
		(27 "Margin" user)
		(31 "F.CrtYd" user "Package Geometry/Place Bound Top")
		(29 "B.CrtYd" user "Package Geometry/Place Bound Bottom")
		(35 "F.Fab" user "Ref Des/Assembly Top")
		(33 "B.Fab" user "Ref Des/Assembly Bottom")
	)
	(footprint ""
		(layer "F.Cu")
		(at 206.019146 -120.771666)
		(property "Reference" "R811"
			(at 0 0 0)
			(layer "F.SilkS")
			(hide yes)
			(effects
				(font
					(size 1.27 1.27)
				)
			)
		)
		(property "Value" "4K7R2F-GP"
			(at 0.064008 -3.993896 0)
			(unlocked yes)
			(layer "F.Fab")
			(hide yes)
			(effects
				(font
					(size 1.016 1.016)
					(thickness 0.1524)
				)
			)
		)
		(property "Device Type" "R402H16"
			(at 0.064008 -5.517896 0)
			(unlocked yes)
			(layer "F.Fab")
			(hide yes)
			(effects
				(font
					(size 1.016 1.016)
					(thickness 0.1524)
				)
			)
		)
		(duplicate_pad_numbers_are_jumpers no)
		(fp_line
			(start -0.508 -0.9398)
			(end -0.508 0.9398)
			(stroke
				(width 0.1524)
				(type default)
			)
			(layer "F.SilkS")
		)
		(fp_line
			(start 0.508 -0.9398)
			(end -0.508 -0.9398)
			(stroke
				(width 0.1524)
				(type default)
			)
			(layer "F.SilkS")
		)
		(fp_rect
			(start -0.508 0.9398)
			(end 0.508 -0.9398)
			(stroke
				(width 0)
				(type default)
			)
			(fill no)
			(layer "F.CrtYd")
		)
		(fp_rect
			(start -0.508 0.9398)
			(end 0.508 -0.9398)
			(stroke
				(width 0)
				(type default)
			)
			(fill no)
			(layer "F.Fab")
		)
		(pad "1" smd custom
			(at 0 -0.4445)
			(size 0.1397 0.1397)
			(layers "F.Cu" "F.Mask" "F.Paste")
			(net "M2_1_ALERT#")
			(options
				(clearance outline)
				(anchor circle)
			)
			(primitives
				(gr_poly
					(pts
						(arc
							(start -0.1778 -0.2794)
							(mid -0.249642 -0.249642)
							(end -0.2794 -0.1778)
						)
						(arc
							(start -0.2794 0.1778)
							(mid -0.249642 0.249642)
							(end -0.1778 0.2794)
						)
						(arc
							(start 0.1778 0.2794)
							(mid 0.249642 0.249642)
							(end 0.2794 0.1778)
						)
						(arc
							(start 0.2794 -0.1778)
							(mid 0.249642 -0.249642)
							(end 0.1778 -0.2794)
						)
					)
					(width 0)
					(fill yes)
				)
			)
		)
		(pad "2" smd custom
			(at 0 0.4445)
			(size 0.1397 0.1397)
			(layers "F.Cu" "F.Mask" "F.Paste")
			(net "P1V8_STBY")
			(options
				(clearance outline)
				(anchor circle)
			)
			(primitives
				(gr_poly
					(pts
						(arc
							(start -0.1778 -0.2794)
							(mid -0.249642 -0.249642)
							(end -0.2794 -0.1778)
						)
						(arc
							(start -0.2794 0.1778)
							(mid -0.249642 0.249642)
							(end -0.1778 0.2794)
						)
						(arc
							(start 0.1778 0.2794)
							(mid 0.249642 0.249642)
							(end 0.2794 0.1778)
						)
						(arc
							(start 0.2794 -0.1778)
							(mid 0.249642 -0.249642)
							(end 0.1778 -0.2794)
						)
					)
					(width 0)
					(fill yes)
				)
			)
		)
	)
	(footprint ""
		(layer "F.Cu")
		(at 83.358228 -94.937072 90)
		(property "Reference" "VIA16"
			(at 0 0 90)
			(layer "F.SilkS")
			(hide yes)
			(effects
				(font
					(size 1.27 1.27)
				)
			)
		)
		(property "Value" "85OHM-8L-1D6MM-L16L18-GP"
			(at 4.064 0.6096 90)
			(unlocked yes)
			(layer "F.Fab")
			(hide yes)
			(effects
				(font
					(size 1.016 1.016)
					(thickness 0.1524)
				)
			)
		)
		(property "Device Type" "VIA-PCIE-4P-368076"
			(at 4.064 -0.9144 90)
			(unlocked yes)
			(layer "F.Fab")
			(hide yes)
			(effects
				(font
					(size 1.016 1.016)
					(thickness 0.1524)
				)
			)
		)
		(duplicate_pad_numbers_are_jumpers no)
		(fp_rect
			(start -1.8415 0.381)
			(end 1.8415 -0.381)
			(stroke
				(width 0)
				(type default)
			)
			(fill no)
			(layer "F.CrtYd")
		)
		(fp_rect
			(start -1.8415 0.381)
			(end 1.8415 -0.381)
			(stroke
				(width 0)
				(type default)
			)
			(fill no)
			(layer "F.Fab")
		)
		(pad "1" thru_hole circle
			(at -1.4605 0 90)
			(size 0.508 0.508)
			(drill 0.254)
			(layers "*.Cu" "*.Mask")
			(remove_unused_layers no)
			(net "GND")
			(clearance 0.127)
			(thermal_gap 0.127)
		)
		(pad "2" thru_hole circle
			(at -0.4445 0 90)
			(size 0.508 0.508)
			(drill 0.254)
			(layers "*.Cu" "*.Mask")
			(remove_unused_layers no)
			(net "PCIE_IOM_TO_COMP_23_DP")
			(clearance 0.127)
			(thermal_gap 0.127)
		)
		(pad "3" thru_hole circle
			(at 0.4445 0 90)
			(size 0.508 0.508)
			(drill 0.254)
			(layers "*.Cu" "*.Mask")
			(remove_unused_layers no)
			(net "PCIE_IOM_TO_COMP_23_DN")
			(clearance 0.127)
			(thermal_gap 0.127)
		)
		(pad "4" thru_hole circle
			(at 1.4605 0 90)
			(size 0.508 0.508)
			(drill 0.254)
			(layers "*.Cu" "*.Mask")
			(remove_unused_layers no)
			(net "GND")
			(clearance 0.127)
			(thermal_gap 0.127)
		)
	)
	(footprint ""
		(layer "F.Cu")
		(at 10.986008 -167.616886 90)
		(property "Reference" "C228"
			(at 0 0 90)
			(layer "F.SilkS")
			(hide yes)
			(effects
				(font
					(size 1.27 1.27)
				)
			)
		)
		(property "Value" "SC470P50V2KX-3GP"
			(at 1.1811 -2.7051 90)
			(unlocked yes)
			(layer "F.Fab")
			(hide yes)
			(effects
				(font
					(size 1.016 1.016)
					(thickness 0.1524)
				)
			)
		)
		(property "Device Type" "C402H22"
			(at 1.1811 -4.2291 90)
			(unlocked yes)
			(layer "F.Fab")
			(hide yes)
			(effects
				(font
					(size 1.016 1.016)
					(thickness 0.1524)
				)
			)
		)
		(duplicate_pad_numbers_are_jumpers no)
		(fp_rect
			(start -0.4318 0.9525)
			(end 0.4318 -0.9525)
			(stroke
				(width 0)
				(type default)
			)
			(fill no)
			(layer "F.CrtYd")
		)
		(fp_rect
			(start -0.4318 0.9525)
			(end 0.4318 -0.9525)
			(stroke
				(width 0)
				(type default)
			)
			(fill no)
			(layer "F.Fab")
		)
		(pad "1" smd custom
			(at 0 -0.4445 90)
			(size 0.1524 0.1524)
			(layers "F.Cu" "F.Mask" "F.Paste")
			(net "GND")
			(options
				(clearance outline)
				(anchor circle)
			)
			(primitives
				(gr_poly
					(pts
						(arc
							(start 0.3048 -0.2032)
							(mid 0.275042 -0.275042)
							(end 0.2032 -0.3048)
						)
						(arc
							(start -0.2032 -0.3048)
							(mid -0.275042 -0.275042)
							(end -0.3048 -0.2032)
						)
						(arc
							(start -0.3048 0.2032)
							(mid -0.275042 0.275042)
							(end -0.2032 0.3048)
						)
						(arc
							(start 0.2032 0.3048)
							(mid 0.275042 0.275042)
							(end 0.3048 0.2032)
						)
					)
					(width 0)
					(fill yes)
				)
			)
		)
		(pad "2" smd custom
			(at 0 0.4445 90)
			(size 0.1524 0.1524)
			(layers "F.Cu" "F.Mask" "F.Paste")
			(net "TPS74801_P1V2_STBY_SS")
			(options
				(clearance outline)
				(anchor circle)
			)
			(primitives
				(gr_poly
					(pts
						(arc
							(start 0.3048 -0.2032)
							(mid 0.275042 -0.275042)
							(end 0.2032 -0.3048)
						)
						(arc
							(start -0.2032 -0.3048)
							(mid -0.275042 -0.275042)
							(end -0.3048 -0.2032)
						)
						(arc
							(start -0.3048 0.2032)
							(mid -0.275042 0.275042)
							(end -0.2032 0.3048)
						)
						(arc
							(start 0.2032 0.3048)
							(mid 0.275042 0.275042)
							(end 0.3048 0.2032)
						)
					)
					(width 0)
					(fill yes)
				)
			)
		)
	)
	(footprint ""
		(layer "F.Cu")
		(at 67.945 -162.433 -90)
		(property "Reference" "R774"
			(at 0 0 270)
			(layer "F.SilkS")
			(hide yes)
			(effects
				(font
					(size 1.27 1.27)
				)
			)
		)
		(property "Value" "1KR2F-3-GP"
			(at 0.064008 -3.993896 270)
			(unlocked yes)
			(layer "F.Fab")
			(hide yes)
			(effects
				(font
					(size 1.016 1.016)
					(thickness 0.1524)
				)
			)
		)
		(property "Device Type" "R402H16"
			(at 0.064008 -5.517896 270)
			(unlocked yes)
			(layer "F.Fab")
			(hide yes)
			(effects
				(font
					(size 1.016 1.016)
					(thickness 0.1524)
				)
			)
		)
		(duplicate_pad_numbers_are_jumpers no)
		(fp_line
			(start -0.508 -0.9398)
			(end -0.508 0.9398)
			(stroke
				(width 0.1524)
				(type default)
			)
			(layer "F.SilkS")
		)
		(fp_line
			(start 0.508 -0.9398)
			(end -0.508 -0.9398)
			(stroke
				(width 0.1524)
				(type default)
			)
			(layer "F.SilkS")
		)
		(fp_rect
			(start -0.508 0.9398)
			(end 0.508 -0.9398)
			(stroke
				(width 0)
				(type default)
			)
			(fill no)
			(layer "F.CrtYd")
		)
		(fp_rect
			(start -0.508 0.9398)
			(end 0.508 -0.9398)
			(stroke
				(width 0)
				(type default)
			)
			(fill no)
			(layer "F.Fab")
		)
		(pad "1" smd custom
			(at 0 -0.4445 270)
			(size 0.1397 0.1397)
			(layers "F.Cu" "F.Mask" "F.Paste")
			(net "P1V15_STBY")
			(options
				(clearance outline)
				(anchor circle)
			)
			(primitives
				(gr_poly
					(pts
						(arc
							(start -0.1778 -0.2794)
							(mid -0.249642 -0.249642)
							(end -0.2794 -0.1778)
						)
						(arc
							(start -0.2794 0.1778)
							(mid -0.249642 0.249642)
							(end -0.1778 0.2794)
						)
						(arc
							(start 0.1778 0.2794)
							(mid 0.249642 0.249642)
							(end 0.2794 0.1778)
						)
						(arc
							(start 0.2794 -0.1778)
							(mid 0.249642 -0.249642)
							(end 0.1778 -0.2794)
						)
					)
					(width 0)
					(fill yes)
				)
			)
		)
		(pad "2" smd custom
			(at 0 0.4445 270)
			(size 0.1397 0.1397)
			(layers "F.Cu" "F.Mask" "F.Paste")
			(net "ADC_P1V15_STBY")
			(options
				(clearance outline)
				(anchor circle)
			)
			(primitives
				(gr_poly
					(pts
						(arc
							(start -0.1778 -0.2794)
							(mid -0.249642 -0.249642)
							(end -0.2794 -0.1778)
						)
						(arc
							(start -0.2794 0.1778)
							(mid -0.249642 0.249642)
							(end -0.1778 0.2794)
						)
						(arc
							(start 0.1778 0.2794)
							(mid 0.249642 0.249642)
							(end 0.2794 0.1778)
						)
						(arc
							(start 0.2794 -0.1778)
							(mid 0.249642 -0.249642)
							(end 0.1778 -0.2794)
						)
					)
					(width 0)
					(fill yes)
				)
			)
		)
	)
	(footprint ""
		(layer "F.Cu")
		(at 8.879332 -136.716516 90)
		(property "Reference" "R207"
			(at 0 0 90)
			(layer "F.SilkS")
			(hide yes)
			(effects
				(font
					(size 1.27 1.27)
				)
			)
		)
		(property "Value" "120R2F-GP"
			(at 0.064008 -3.993896 90)
			(unlocked yes)
			(layer "F.Fab")
			(hide yes)
			(effects
				(font
					(size 1.016 1.016)
					(thickness 0.1524)
				)
			)
		)
		(property "Device Type" "R402H16"
			(at 0.064008 -5.517896 90)
			(unlocked yes)
			(layer "F.Fab")
			(hide yes)
			(effects
				(font
					(size 1.016 1.016)
					(thickness 0.1524)
				)
			)
		)
		(duplicate_pad_numbers_are_jumpers no)
		(fp_line
			(start 0.508 -0.9398)
			(end -0.508 -0.9398)
			(stroke
				(width 0.1524)
				(type default)
			)
			(layer "F.SilkS")
		)
		(fp_line
			(start -0.508 -0.9398)
			(end -0.508 0.9398)
			(stroke
				(width 0.1524)
				(type default)
			)
			(layer "F.SilkS")
		)
		(fp_rect
			(start -0.508 0.9398)
			(end 0.508 -0.9398)
			(stroke
				(width 0)
				(type default)
			)
			(fill no)
			(layer "F.CrtYd")
		)
		(fp_rect
			(start -0.508 0.9398)
			(end 0.508 -0.9398)
			(stroke
				(width 0)
				(type default)
			)
			(fill no)
			(layer "F.Fab")
		)
		(pad "1" smd custom
			(at 0 -0.4445 90)
			(size 0.1397 0.1397)
			(layers "F.Cu" "F.Mask" "F.Paste")
			(net "GND")
			(options
				(clearance outline)
				(anchor circle)
			)
			(primitives
				(gr_poly
					(pts
						(arc
							(start -0.1778 -0.2794)
							(mid -0.249642 -0.249642)
							(end -0.2794 -0.1778)
						)
						(arc
							(start -0.2794 0.1778)
							(mid -0.249642 0.249642)
							(end -0.1778 0.2794)
						)
						(arc
							(start 0.1778 0.2794)
							(mid 0.249642 0.249642)
							(end 0.2794 0.1778)
						)
						(arc
							(start 0.2794 -0.1778)
							(mid 0.249642 -0.249642)
							(end 0.1778 -0.2794)
						)
					)
					(width 0)
					(fill yes)
				)
			)
		)
		(pad "2" smd custom
			(at 0 0.4445 90)
			(size 0.1397 0.1397)
			(layers "F.Cu" "F.Mask" "F.Paste")
			(net "DDR4_RST_N")
			(options
				(clearance outline)
				(anchor circle)
			)
			(primitives
				(gr_poly
					(pts
						(arc
							(start -0.1778 -0.2794)
							(mid -0.249642 -0.249642)
							(end -0.2794 -0.1778)
						)
						(arc
							(start -0.2794 0.1778)
							(mid -0.249642 0.249642)
							(end -0.1778 0.2794)
						)
						(arc
							(start 0.1778 0.2794)
							(mid 0.249642 0.249642)
							(end 0.2794 0.1778)
						)
						(arc
							(start 0.2794 -0.1778)
							(mid 0.249642 -0.249642)
							(end 0.1778 -0.2794)
						)
					)
					(width 0)
					(fill yes)
				)
			)
		)
	)
	(footprint ""
		(layer "F.Cu")
		(at 217.067384 -40.85209)
		(property "Reference" "R471"
			(at 0 0 0)
			(layer "F.SilkS")
			(hide yes)
			(effects
				(font
					(size 1.27 1.27)
				)
			)
		)
		(property "Value" "15KR2F-GP"
			(at 0.064008 -3.993896 0)
			(unlocked yes)
			(layer "F.Fab")
			(hide yes)
			(effects
				(font
					(size 1.016 1.016)
					(thickness 0.1524)
				)
			)
		)
		(property "Device Type" "R402H16"
			(at 0.064008 -5.517896 0)
			(unlocked yes)
			(layer "F.Fab")
			(hide yes)
			(effects
				(font
					(size 1.016 1.016)
					(thickness 0.1524)
				)
			)
		)
		(duplicate_pad_numbers_are_jumpers no)
		(fp_line
			(start -0.508 -0.9398)
			(end -0.508 0.9398)
			(stroke
				(width 0.1524)
				(type default)
			)
			(layer "F.SilkS")
		)
		(fp_line
			(start 0.508 -0.9398)
			(end -0.508 -0.9398)
			(stroke
				(width 0.1524)
				(type default)
			)
			(layer "F.SilkS")
		)
		(fp_rect
			(start -0.508 0.9398)
			(end 0.508 -0.9398)
			(stroke
				(width 0)
				(type default)
			)
			(fill no)
			(layer "F.CrtYd")
		)
		(fp_rect
			(start -0.508 0.9398)
			(end 0.508 -0.9398)
			(stroke
				(width 0)
				(type default)
			)
			(fill no)
			(layer "F.Fab")
		)
		(pad "1" smd custom
			(at 0 -0.4445)
			(size 0.1397 0.1397)
			(layers "F.Cu" "F.Mask" "F.Paste")
			(net "PWRGD_P5V_STBY")
			(options
				(clearance outline)
				(anchor circle)
			)
			(primitives
				(gr_poly
					(pts
						(arc
							(start -0.1778 -0.2794)
							(mid -0.249642 -0.249642)
							(end -0.2794 -0.1778)
						)
						(arc
							(start -0.2794 0.1778)
							(mid -0.249642 0.249642)
							(end -0.1778 0.2794)
						)
						(arc
							(start 0.1778 0.2794)
							(mid 0.249642 0.249642)
							(end 0.2794 0.1778)
						)
						(arc
							(start 0.2794 -0.1778)
							(mid 0.249642 -0.249642)
							(end 0.1778 -0.2794)
						)
					)
					(width 0)
					(fill yes)
				)
			)
		)
		(pad "2" smd custom
			(at 0 0.4445)
			(size 0.1397 0.1397)
			(layers "F.Cu" "F.Mask" "F.Paste")
			(net "GND")
			(options
				(clearance outline)
				(anchor circle)
			)
			(primitives
				(gr_poly
					(pts
						(arc
							(start -0.1778 -0.2794)
							(mid -0.249642 -0.249642)
							(end -0.2794 -0.1778)
						)
						(arc
							(start -0.2794 0.1778)
							(mid -0.249642 0.249642)
							(end -0.1778 0.2794)
						)
						(arc
							(start 0.1778 0.2794)
							(mid 0.249642 0.249642)
							(end 0.2794 0.1778)
						)
						(arc
							(start 0.2794 -0.1778)
							(mid 0.249642 -0.249642)
							(end 0.1778 -0.2794)
						)
					)
					(width 0)
					(fill yes)
				)
			)
		)
	)
	(footprint ""
		(layer "F.Cu")
		(at 211.473288 -44.367958 180)
		(property "Reference" "R473"
			(at 0 0 180)
			(layer "F.SilkS")
			(hide yes)
			(effects
				(font
					(size 1.27 1.27)
				)
			)
		)
		(property "Value" "10R3F-GP"
			(at -0.0254 -2.5146 180)
			(unlocked yes)
			(layer "F.Fab")
			(hide yes)
			(effects
				(font
					(size 1.016 1.016)
					(thickness 0.1524)
				)
			)
		)
		(property "Device Type" "R603H22"
			(at -0.0254 -4.0386 180)
			(unlocked yes)
			(layer "F.Fab")
			(hide yes)
			(effects
				(font
					(size 1.016 1.016)
					(thickness 0.1524)
				)
			)
		)
		(duplicate_pad_numbers_are_jumpers no)
		(fp_line
			(start 0.2032 0)
			(end 0.4826 0)
			(stroke
				(width 0.2032)
				(type default)
			)
			(layer "F.SilkS")
		)
		(fp_line
			(start -0.4826 0)
			(end -0.2032 0)
			(stroke
				(width 0.2032)
				(type default)
			)
			(layer "F.SilkS")
		)
		(fp_rect
			(start -0.5842 1.3335)
			(end 0.5842 -1.3335)
			(stroke
				(width 0)
				(type default)
			)
			(fill no)
			(layer "F.CrtYd")
		)
		(fp_rect
			(start -0.5842 1.3335)
			(end 0.5842 -1.3335)
			(stroke
				(width 0)
				(type default)
			)
			(fill no)
			(layer "F.Fab")
		)
		(pad "1" smd custom
			(at 0 -0.762 180)
			(size 0.2159 0.2159)
			(layers "F.Cu" "F.Mask" "F.Paste")
			(net "P5V_CC")
			(options
				(clearance outline)
				(anchor circle)
			)
			(primitives
				(gr_poly
					(pts
						(arc
							(start -0.3302 -0.4318)
							(mid -0.402042 -0.402042)
							(end -0.4318 -0.3302)
						)
						(arc
							(start -0.4318 0.3302)
							(mid -0.402042 0.402042)
							(end -0.3302 0.4318)
						)
						(arc
							(start 0.3302 0.4318)
							(mid 0.402042 0.402042)
							(end 0.4318 0.3302)
						)
						(arc
							(start 0.4318 -0.3302)
							(mid 0.402042 -0.402042)
							(end 0.3302 -0.4318)
						)
					)
					(width 0)
					(fill yes)
				)
			)
		)
		(pad "2" smd custom
			(at 0 0.762 180)
			(size 0.2159 0.2159)
			(layers "F.Cu" "F.Mask" "F.Paste")
			(net "P5V_VFB_R")
			(options
				(clearance outline)
				(anchor circle)
			)
			(primitives
				(gr_poly
					(pts
						(arc
							(start -0.3302 -0.4318)
							(mid -0.402042 -0.402042)
							(end -0.4318 -0.3302)
						)
						(arc
							(start -0.4318 0.3302)
							(mid -0.402042 0.402042)
							(end -0.3302 0.4318)
						)
						(arc
							(start 0.3302 0.4318)
							(mid 0.402042 0.402042)
							(end 0.4318 0.3302)
						)
						(arc
							(start 0.4318 -0.3302)
							(mid 0.402042 -0.402042)
							(end 0.3302 -0.4318)
						)
					)
					(width 0)
					(fill yes)
				)
			)
		)
	)
)
